(kicad_pcb
	(version 20260206)
	(generator "pcbnew")
	(generator_version "10.0")
	(general
		(thickness 1.6)
		(legacy_teardrops no)
	)
	(paper "A4")
	(title_block
		(title "04192023_DAF0TMB3IC0_F0TG_MB_C_brd_V02_OCP.brd")
		(comment 1 "Grand Teton / footprints 4613-4617 of 8354")
	)
	(layers
		(0 "F.Cu" signal "TOP")
		(4 "In1.Cu" signal "GND")
		(6 "In2.Cu" signal "IN1")
		(8 "In3.Cu" signal "GND1")
		(10 "In4.Cu" signal "IN2")
		(12 "In5.Cu" signal "GND2")
		(14 "In6.Cu" signal "IN3")
		(16 "In7.Cu" signal "GND3")
		(18 "In8.Cu" signal "VCC")
		(20 "In9.Cu" signal "VCC1")
		(22 "In10.Cu" signal "GND4")
		(24 "In11.Cu" signal "IN4")
		(26 "In12.Cu" signal "GND5")
		(28 "In13.Cu" signal "IN5")
		(30 "In14.Cu" signal "GND6")
		(32 "In15.Cu" signal "IN6")
		(34 "In16.Cu" signal "GND7")
		(2 "B.Cu" signal "BOTTOM")
		(9 "F.Adhes" user "F.Adhesive")
		(11 "B.Adhes" user "B.Adhesive")
		(13 "F.Paste" user "Package Geometry/Pastemask Top")
		(15 "B.Paste" user "Package Geometry/Pastemask Bottom")
		(5 "F.SilkS" user "Ref Des/Silkscreen Top")
		(7 "B.SilkS" user "Ref Des/Silkscreen Bottom")
		(1 "F.Mask" user "Board Geometry/Soldermask Top")
		(3 "B.Mask" user "Board Geometry/Soldermask Bottom")
		(17 "Dwgs.User" user "User.Drawings")
		(19 "Cmts.User" user "User.Comments")
		(21 "Eco1.User" user "User.Eco1")
		(23 "Eco2.User" user "User.Eco2")
		(25 "Edge.Cuts" user "Board Geometry/Outline")
		(27 "Margin" user)
		(31 "F.CrtYd" user "Package Geometry/Place Bound Top")
		(29 "B.CrtYd" user "Package Geometry/Place Bound Bottom")
		(35 "F.Fab" user "Ref Des/Assembly Top")
		(33 "B.Fab" user "Ref Des/Assembly Bottom")
	)
	(footprint ""
		(layer "F.Cu")
		(at 149.987254 -23.284942 -90)
		(property "Reference" "R6026"
			(at 0 0 270)
			(layer "F.SilkS")
			(hide yes)
			(effects
				(font
					(size 1.27 1.27)
				)
			)
		)
		(property "Value" ""
			(at 0 0 270)
			(layer "F.Fab")
			(effects
				(font
					(size 1.27 1.27)
				)
			)
		)
		(duplicate_pad_numbers_are_jumpers no)
		(fp_line
			(start -0.7874 0.4064)
			(end -0.7874 -0.4064)
			(stroke
				(width 0.1524)
				(type default)
			)
			(layer "F.SilkS")
		)
		(fp_line
			(start 0.7874 0.4064)
			(end -0.7874 0.4064)
			(stroke
				(width 0.1524)
				(type default)
			)
			(layer "F.SilkS")
		)
		(fp_line
			(start -0.7874 -0.4064)
			(end 0.7874 -0.4064)
			(stroke
				(width 0.1524)
				(type default)
			)
			(layer "F.SilkS")
		)
		(fp_line
			(start 0.7874 -0.4064)
			(end 0.7874 0.4064)
			(stroke
				(width 0.1524)
				(type default)
			)
			(layer "F.SilkS")
		)
		(fp_line
			(start -0.67945 0.3048)
			(end -0.67945 -0.305054)
			(stroke
				(width 0.1)
				(type default)
			)
			(layer "F.Fab")
		)
		(fp_line
			(start -0.12065 0.3048)
			(end -0.67945 0.3048)
			(stroke
				(width 0.1)
				(type default)
			)
			(layer "F.Fab")
		)
		(fp_line
			(start 0.120396 0.3048)
			(end 0.120396 0.2794)
			(stroke
				(width 0.1)
				(type default)
			)
			(layer "F.Fab")
		)
		(fp_line
			(start 0.67945 0.3048)
			(end 0.120396 0.3048)
			(stroke
				(width 0.1)
				(type default)
			)
			(layer "F.Fab")
		)
		(fp_line
			(start -0.12065 0.2794)
			(end -0.12065 0.3048)
			(stroke
				(width 0.1)
				(type default)
			)
			(layer "F.Fab")
		)
		(fp_line
			(start 0.120396 0.2794)
			(end -0.12065 0.2794)
			(stroke
				(width 0.1)
				(type default)
			)
			(layer "F.Fab")
		)
		(fp_line
			(start -0.12065 -0.2794)
			(end 0.12065 -0.2794)
			(stroke
				(width 0.1)
				(type default)
			)
			(layer "F.Fab")
		)
		(fp_line
			(start 0.12065 -0.2794)
			(end 0.12065 -0.3048)
			(stroke
				(width 0.1)
				(type default)
			)
			(layer "F.Fab")
		)
		(fp_line
			(start 0.12065 -0.3048)
			(end 0.67945 -0.3048)
			(stroke
				(width 0.1)
				(type default)
			)
			(layer "F.Fab")
		)
		(fp_line
			(start 0.67945 -0.3048)
			(end 0.67945 0.3048)
			(stroke
				(width 0.1)
				(type default)
			)
			(layer "F.Fab")
		)
		(fp_line
			(start -0.67945 -0.305054)
			(end -0.12065 -0.305054)
			(stroke
				(width 0.1)
				(type default)
			)
			(layer "F.Fab")
		)
		(fp_line
			(start -0.12065 -0.305054)
			(end -0.12065 -0.2794)
			(stroke
				(width 0.1)
				(type default)
			)
			(layer "F.Fab")
		)
		(pad "1" smd circle
			(at -0.40005 0 270)
			(size 0 0)
			(layers "F.Cu" "F.Mask" "F.Paste")
			(net "SGPIO_SCM_INTR_N")
		)
		(pad "2" smd circle
			(at 0.40005 0 270)
			(size 0 0)
			(layers "F.Cu" "F.Mask" "F.Paste")
			(net "SGPIO_SCM_INTR_R1_N")
		)
	)
	(footprint ""
		(layer "F.Cu")
		(at 180.9242 -96.103948 90)
		(property "Reference" "R246"
			(at 0 0 90)
			(layer "F.SilkS")
			(hide yes)
			(effects
				(font
					(size 1.27 1.27)
				)
			)
		)
		(property "Value" ""
			(at 0 0 90)
			(layer "F.Fab")
			(effects
				(font
					(size 1.27 1.27)
				)
			)
		)
		(duplicate_pad_numbers_are_jumpers no)
		(fp_line
			(start 0.7874 -0.4064)
			(end 0.7874 0.4064)
			(stroke
				(width 0.1524)
				(type default)
			)
			(layer "F.SilkS")
		)
		(fp_line
			(start -0.7874 -0.4064)
			(end 0.7874 -0.4064)
			(stroke
				(width 0.1524)
				(type default)
			)
			(layer "F.SilkS")
		)
		(fp_line
			(start 0.7874 0.4064)
			(end -0.7874 0.4064)
			(stroke
				(width 0.1524)
				(type default)
			)
			(layer "F.SilkS")
		)
		(fp_line
			(start -0.7874 0.4064)
			(end -0.7874 -0.4064)
			(stroke
				(width 0.1524)
				(type default)
			)
			(layer "F.SilkS")
		)
		(fp_line
			(start -0.12065 -0.305054)
			(end -0.12065 -0.2794)
			(stroke
				(width 0.1)
				(type default)
			)
			(layer "F.Fab")
		)
		(fp_line
			(start -0.67945 -0.305054)
			(end -0.12065 -0.305054)
			(stroke
				(width 0.1)
				(type default)
			)
			(layer "F.Fab")
		)
		(fp_line
			(start 0.67945 -0.3048)
			(end 0.67945 0.3048)
			(stroke
				(width 0.1)
				(type default)
			)
			(layer "F.Fab")
		)
		(fp_line
			(start 0.12065 -0.3048)
			(end 0.67945 -0.3048)
			(stroke
				(width 0.1)
				(type default)
			)
			(layer "F.Fab")
		)
		(fp_line
			(start 0.12065 -0.2794)
			(end 0.12065 -0.3048)
			(stroke
				(width 0.1)
				(type default)
			)
			(layer "F.Fab")
		)
		(fp_line
			(start -0.12065 -0.2794)
			(end 0.12065 -0.2794)
			(stroke
				(width 0.1)
				(type default)
			)
			(layer "F.Fab")
		)
		(fp_line
			(start 0.120396 0.2794)
			(end -0.12065 0.2794)
			(stroke
				(width 0.1)
				(type default)
			)
			(layer "F.Fab")
		)
		(fp_line
			(start -0.12065 0.2794)
			(end -0.12065 0.3048)
			(stroke
				(width 0.1)
				(type default)
			)
			(layer "F.Fab")
		)
		(fp_line
			(start 0.67945 0.3048)
			(end 0.120396 0.3048)
			(stroke
				(width 0.1)
				(type default)
			)
			(layer "F.Fab")
		)
		(fp_line
			(start 0.120396 0.3048)
			(end 0.120396 0.2794)
			(stroke
				(width 0.1)
				(type default)
			)
			(layer "F.Fab")
		)
		(fp_line
			(start -0.12065 0.3048)
			(end -0.67945 0.3048)
			(stroke
				(width 0.1)
				(type default)
			)
			(layer "F.Fab")
		)
		(fp_line
			(start -0.67945 0.3048)
			(end -0.67945 -0.305054)
			(stroke
				(width 0.1)
				(type default)
			)
			(layer "F.Fab")
		)
		(pad "1" smd circle
			(at -0.40005 0 90)
			(size 0 0)
			(layers "F.Cu" "F.Mask" "F.Paste")
			(net "IRQ_TPM_SPI_R_N")
		)
		(pad "2" smd circle
			(at 0.40005 0 90)
			(size 0 0)
			(layers "F.Cu" "F.Mask" "F.Paste")
			(net "IRQ_TPM_SPI_R1_N")
		)
	)
	(footprint ""
		(layer "F.Cu")
		(at 52.011072 -401.989036 90)
		(property "Reference" "C7038"
			(at 0 0 90)
			(layer "F.SilkS")
			(hide yes)
			(effects
				(font
					(size 1.27 1.27)
				)
			)
		)
		(property "Value" ""
			(at 0 0 90)
			(layer "F.Fab")
			(effects
				(font
					(size 1.27 1.27)
				)
			)
		)
		(duplicate_pad_numbers_are_jumpers no)
		(fp_line
			(start 1.524 -0.762)
			(end 1.524 0.762)
			(stroke
				(width 0.1524)
				(type default)
			)
			(layer "F.SilkS")
		)
		(fp_line
			(start -1.524 -0.762)
			(end 1.524 -0.762)
			(stroke
				(width 0.1524)
				(type default)
			)
			(layer "F.SilkS")
		)
		(fp_line
			(start 1.524 0.762)
			(end -1.524 0.762)
			(stroke
				(width 0.1524)
				(type default)
			)
			(layer "F.SilkS")
		)
		(fp_line
			(start -1.524 0.762)
			(end -1.524 -0.762)
			(stroke
				(width 0.1524)
				(type default)
			)
			(layer "F.SilkS")
		)
		(fp_line
			(start 1.1049 -0.724916)
			(end -1.1049 -0.724916)
			(stroke
				(width 0.1)
				(type default)
			)
			(layer "F.Fab")
		)
		(fp_line
			(start -1.1049 -0.724916)
			(end -1.1049 0.724916)
			(stroke
				(width 0.1)
				(type default)
			)
			(layer "F.Fab")
		)
		(fp_line
			(start 1.1049 0.724916)
			(end 1.1049 -0.724916)
			(stroke
				(width 0.1)
				(type default)
			)
			(layer "F.Fab")
		)
		(fp_line
			(start -1.1049 0.724916)
			(end 1.1049 0.724916)
			(stroke
				(width 0.1)
				(type default)
			)
			(layer "F.Fab")
		)
		(pad "1" smd rect
			(at -0.889 0 270)
			(size 1.016 1.27)
			(layers "F.Cu" "F.Mask" "F.Paste")
			(net "P0V9_CPU1_RT_2D")
		)
		(pad "2" smd rect
			(at 0.889 0 270)
			(size 1.016 1.27)
			(layers "F.Cu" "F.Mask" "F.Paste")
			(net "GND")
		)
	)
	(footprint ""
		(layer "F.Cu")
		(at 302.1584 -363.982)
		(property "Reference" "R8057"
			(at 0 0 0)
			(layer "F.SilkS")
			(hide yes)
			(effects
				(font
					(size 1.27 1.27)
				)
			)
		)
		(property "Value" ""
			(at 0 0 0)
			(layer "F.Fab")
			(effects
				(font
					(size 1.27 1.27)
				)
			)
		)
		(duplicate_pad_numbers_are_jumpers no)
		(fp_line
			(start -0.7874 -0.4064)
			(end 0.7874 -0.4064)
			(stroke
				(width 0.1524)
				(type default)
			)
			(layer "F.SilkS")
		)
		(fp_line
			(start -0.7874 0.4064)
			(end -0.7874 -0.4064)
			(stroke
				(width 0.1524)
				(type default)
			)
			(layer "F.SilkS")
		)
		(fp_line
			(start 0.7874 -0.4064)
			(end 0.7874 0.4064)
			(stroke
				(width 0.1524)
				(type default)
			)
			(layer "F.SilkS")
		)
		(fp_line
			(start 0.7874 0.4064)
			(end -0.7874 0.4064)
			(stroke
				(width 0.1524)
				(type default)
			)
			(layer "F.SilkS")
		)
		(fp_line
			(start -0.67945 -0.305054)
			(end -0.12065 -0.305054)
			(stroke
				(width 0.1)
				(type default)
			)
			(layer "F.Fab")
		)
		(fp_line
			(start -0.67945 0.3048)
			(end -0.67945 -0.305054)
			(stroke
				(width 0.1)
				(type default)
			)
			(layer "F.Fab")
		)
		(fp_line
			(start -0.12065 -0.305054)
			(end -0.12065 -0.2794)
			(stroke
				(width 0.1)
				(type default)
			)
			(layer "F.Fab")
		)
		(fp_line
			(start -0.12065 -0.2794)
			(end 0.12065 -0.2794)
			(stroke
				(width 0.1)
				(type default)
			)
			(layer "F.Fab")
		)
		(fp_line
			(start -0.12065 0.2794)
			(end -0.12065 0.3048)
			(stroke
				(width 0.1)
				(type default)
			)
			(layer "F.Fab")
		)
		(fp_line
			(start -0.12065 0.3048)
			(end -0.67945 0.3048)
			(stroke
				(width 0.1)
				(type default)
			)
			(layer "F.Fab")
		)
		(fp_line
			(start 0.120396 0.2794)
			(end -0.12065 0.2794)
			(stroke
				(width 0.1)
				(type default)
			)
			(layer "F.Fab")
		)
		(fp_line
			(start 0.120396 0.3048)
			(end 0.120396 0.2794)
			(stroke
				(width 0.1)
				(type default)
			)
			(layer "F.Fab")
		)
		(fp_line
			(start 0.12065 -0.3048)
			(end 0.67945 -0.3048)
			(stroke
				(width 0.1)
				(type default)
			)
			(layer "F.Fab")
		)
		(fp_line
			(start 0.12065 -0.2794)
			(end 0.12065 -0.3048)
			(stroke
				(width 0.1)
				(type default)
			)
			(layer "F.Fab")
		)
		(fp_line
			(start 0.67945 -0.3048)
			(end 0.67945 0.3048)
			(stroke
				(width 0.1)
				(type default)
			)
			(layer "F.Fab")
		)
		(fp_line
			(start 0.67945 0.3048)
			(end 0.120396 0.3048)
			(stroke
				(width 0.1)
				(type default)
			)
			(layer "F.Fab")
		)
		(pad "1" smd circle
			(at -0.40005 0)
			(size 0 0)
			(layers "F.Cu" "F.Mask" "F.Paste")
			(net "PWRGD_PVDDCR_CPU1_P0")
		)
		(pad "2" smd circle
			(at 0.40005 0)
			(size 0 0)
			(layers "F.Cu" "F.Mask" "F.Paste")
			(net "PWRGD_PVDDCR_CPU1_P0_R")
		)
	)
	(footprint ""
		(layer "F.Cu")
		(at 53.543454 -346.721176)
		(property "Reference" "PU39"
			(at -3.124454 -7.709154 0)
			(unlocked yes)
			(layer "F.SilkS")
			(effects
				(font
					(size 0.7874 0.5842)
					(thickness 0.1524)
				)
				(justify left)
			)
		)
		(property "Value" ""
			(at 0 0 0)
			(layer "F.Fab")
			(effects
				(font
					(size 1.27 1.27)
				)
			)
		)
		(duplicate_pad_numbers_are_jumpers no)
		(fp_line
			(start -2.500122 -2.999994)
			(end -2.24409 -2.999994)
			(stroke
				(width 0.1524)
				(type default)
			)
			(layer "F.SilkS")
		)
		(fp_line
			(start -2.500122 -2.529078)
			(end -2.500122 -2.999994)
			(stroke
				(width 0.1524)
				(type default)
			)
			(layer "F.SilkS")
		)
		(fp_line
			(start -2.500122 0.6604)
			(end -2.500122 0.229108)
			(stroke
				(width 0.1524)
				(type default)
			)
			(layer "F.SilkS")
		)
		(fp_line
			(start -2.500122 2.999994)
			(end -2.500122 2.339594)
			(stroke
				(width 0.1524)
				(type default)
			)
			(layer "F.SilkS")
		)
		(fp_line
			(start -2.2987 2.999994)
			(end -2.500122 2.999994)
			(stroke
				(width 0.1524)
				(type default)
			)
			(layer "F.SilkS")
		)
		(fp_line
			(start 2.31394 -2.999994)
			(end 2.500122 -2.999994)
			(stroke
				(width 0.1524)
				(type default)
			)
			(layer "F.SilkS")
		)
		(fp_line
			(start 2.500122 -2.999994)
			(end 2.500122 -2.44348)
			(stroke
				(width 0.1524)
				(type default)
			)
			(layer "F.SilkS")
		)
		(fp_line
			(start 2.500122 2.339594)
			(end 2.500122 2.999994)
			(stroke
				(width 0.1524)
				(type default)
			)
			(layer "F.SilkS")
		)
		(fp_line
			(start 2.500122 2.999994)
			(end 2.2987 2.999994)
			(stroke
				(width 0.1524)
				(type default)
			)
			(layer "F.SilkS")
		)
		(fp_poly
			(pts
				(xy -2.72923 -2.454148) (xy -3.402838 -2.678684) (xy -2.953766 -3.127756)
			)
			(stroke
				(width 0)
				(type default)
			)
			(fill yes)
			(layer "F.SilkS")
		)
		(fp_line
			(start -2.500122 -2.999994)
			(end 2.500122 -2.999994)
			(stroke
				(width 0.1)
				(type default)
			)
			(layer "F.Fab")
		)
		(fp_line
			(start -2.500122 2.999994)
			(end -2.500122 -2.999994)
			(stroke
				(width 0.1)
				(type default)
			)
			(layer "F.Fab")
		)
		(fp_line
			(start 2.500122 -2.999994)
			(end 2.500122 2.999994)
			(stroke
				(width 0.1)
				(type default)
			)
			(layer "F.Fab")
		)
		(fp_line
			(start 2.500122 2.999994)
			(end -2.500122 2.999994)
			(stroke
				(width 0.1)
				(type default)
			)
			(layer "F.Fab")
		)
		(fp_poly
			(pts
				(xy -4.218432 -2.783078) (xy -4.218432 -1.767078) (xy -3.202432 -2.275078)
			)
			(stroke
				(width 0)
				(type default)
			)
			(fill yes)
			(layer "F.Fab")
		)
		(pad "1" smd rect
			(at -2.400046 -2.275078 90)
			(size 0.2286 0.6096)
			(layers "F.Cu" "F.Mask" "F.Paste")
			(net "PVDDIO_P1_VOS1")
		)
		(pad "2" smd rect
			(at -2.400046 -1.82499 90)
			(size 0.2286 0.6096)
			(layers "F.Cu" "F.Mask" "F.Paste")
			(net "GND")
		)
		(pad "3" smd rect
			(at -2.400046 -1.374902 90)
			(size 0.2286 0.6096)
			(layers "F.Cu" "F.Mask" "F.Paste")
			(net "PVDDIO_P1_VCC1")
		)
		(pad "4" smd rect
			(at -2.400046 -0.925068 90)
			(size 0.2286 0.6096)
			(layers "F.Cu" "F.Mask" "F.Paste")
			(net "PVDDCR_CPU1_P1_PVCC")
		)
		(pad "5" smd rect
			(at -2.400046 -0.47498 90)
			(size 0.2286 0.6096)
			(layers "F.Cu" "F.Mask" "F.Paste")
			(net "GND")
		)
		(pad "6" smd rect
			(at -2.400046 -0.024892 90)
			(size 0.2286 0.6096)
			(layers "F.Cu" "F.Mask" "F.Paste")
			(net "NC_PVDDIO_P1_GL1_1")
		)
		(pad "7_9-20_24" smd circle
			(at 0 1.150112 90)
			(size 0 0)
			(layers "F.Cu" "F.Mask" "F.Paste")
			(net "GND")
		)
		(pad "10_19" smd rect
			(at 0 2.899918 90)
			(size 0.6096 4.318)
			(layers "F.Cu" "F.Mask" "F.Paste")
			(net "SW_PVDDIO_P1_SW1")
		)
		(pad "25_29" smd rect
			(at 1.549908 -1.279906 270)
			(size 2.0574 2.3114)
			(layers "F.Cu" "F.Mask" "F.Paste")
			(net "SW_P12V_AUX_PVDDIO_P1_FLT")
		)
		(pad "30" smd rect
			(at 2.05994 -2.899918)
			(size 0.2286 0.6096)
			(layers "F.Cu" "F.Mask" "F.Paste")
			(net "SW_P12V_AUX_PVDDIO_P1_FLT")
		)
		(pad "31" smd rect
			(at 1.610106 -2.899918)
			(size 0.2286 0.6096)
			(layers "F.Cu" "F.Mask" "F.Paste")
			(net "NC_PVDDIO_P1_DNC1")
		)
		(pad "32" smd rect
			(at 1.160018 -2.899918)
			(size 0.2286 0.6096)
			(layers "F.Cu" "F.Mask" "F.Paste")
			(net "SW_PVDDIO_P1_BOOTR1")
		)
		(pad "33" smd rect
			(at 0.70993 -2.899918)
			(size 0.2286 0.6096)
			(layers "F.Cu" "F.Mask" "F.Paste")
			(net "SW_PVDDIO_P1_BOOT1")
		)
		(pad "34" smd rect
			(at 0.260096 -2.899918)
			(size 0.2286 0.6096)
			(layers "F.Cu" "F.Mask" "F.Paste")
			(net "PVDDIO_P1_PWM1")
		)
		(pad "35" smd rect
			(at -0.189992 -2.899918)
			(size 0.2286 0.6096)
			(layers "F.Cu" "F.Mask" "F.Paste")
			(net "PVDDIO_P1_VCC1")
		)
		(pad "36" smd rect
			(at -0.64008 -2.899918)
			(size 0.2286 0.6096)
			(layers "F.Cu" "F.Mask" "F.Paste")
			(net "PVDDIO_P1_TEMP1")
		)
		(pad "37" smd rect
			(at -1.089914 -2.899918)
			(size 0.2286 0.6096)
			(layers "F.Cu" "F.Mask" "F.Paste")
			(net "PVDDIO_P1_LSET1")
		)
		(pad "38" smd rect
			(at -1.540002 -2.899918)
			(size 0.2286 0.6096)
			(layers "F.Cu" "F.Mask" "F.Paste")
			(net "PVDDIO_P1_IMON1")
		)
		(pad "39" smd rect
			(at -1.99009 -2.899918)
			(size 0.2286 0.6096)
			(layers "F.Cu" "F.Mask" "F.Paste")
			(net "PVDDCR_CPU1_P1_VCCS")
		)
		(pad "40" smd rect
			(at -0.87503 -1.27508)
			(size 1.7526 1.9558)
			(layers "F.Cu" "F.Mask" "F.Paste")
			(net "GND")
		)
		(pad "41" smd rect
			(at -1.525016 0.249936 270)
			(size 0.3048 0.4572)
			(layers "F.Cu" "F.Mask" "F.Paste")
			(net "NC_PVDDIO_P1_GL2_1")
		)
		(zone
			(layer "F.Cu")
			(hatch none 0.5)
			(connect_pads
				(clearance 0)
			)
			(min_thickness 0.25)
			(keepout
				(tracks not_allowed)
				(vias allowed)
				(pads allowed)
				(copperpour not_allowed)
				(footprints allowed)
			)
			(placement
				(enabled no)
				(sheetname "")
			)
			(fill
				(thermal_gap 0.5)
				(thermal_bridge_width 0.5)
				(island_removal_mode 0)
			)
			(polygon
				(pts
					(xy 51.043332 -344.156284) (xy 51.043332 -344.470482) (xy 56.043576 -344.470482) (xy 56.043576 -344.138758)
					(xy 55.753254 -344.138758) (xy 55.753254 -344.176858) (xy 51.333654 -344.176858) (xy 51.333654 -344.156284)
				)
			)
		)
		(zone
			(layer "F.Cu")
			(hatch none 0.5)
			(connect_pads
				(clearance 0)
			)
			(min_thickness 0.25)
			(keepout
				(tracks not_allowed)
				(vias allowed)
				(pads allowed)
				(copperpour not_allowed)
				(footprints allowed)
			)
			(placement
				(enabled no)
				(sheetname "")
			)
			(fill
				(thermal_gap 0.5)
				(thermal_bridge_width 0.5)
				(island_removal_mode 0)
			)
			(polygon
				(pts
					(xy 53.595524 -346.967556) (xy 53.595524 -349.024956) (xy 51.741324 -349.024956) (xy 51.741324 -348.78391)
					(xy 51.499008 -348.78391) (xy 51.499008 -349.265494) (xy 55.350664 -349.265494) (xy 55.350664 -349.080582)
					(xy 53.886862 -349.080582) (xy 53.886862 -346.921582) (xy 56.043576 -346.921582) (xy 56.043576 -346.6719)
					(xy 53.89118 -346.6719)
				)
			)
		)
	)
)
